FILE_TYPE = CONNECTIVITY;
{Allegro Design Entry HDL 17.4-2019 S026 (4007227) 1/17/2022}
"PAGE_NUMBER" = 371;
0"NC";
1"P3V3_AUX\g";
2"P3V3_AUX\g";
3"P3V3_AUX\g";
4"GND\g";
5"P12V_PSU";
6"GND\g";
7"GND\g";
8"P3V3_AUX\g";
9"GND\g";
10"GND\g";
11"P3V3_AUX\g";
12"P3V3_AUX\g";
13"P3V3_AUX\g";
14"GND\g";
15"GND\g";
16"P3V3_AUX\g";
17"GND\g";
18"GND\g";
19"GND\g";
20"GND\g";
21"GND\g";
22"P12V_AUX";
23"P3V3_AUX\g";
24"HSC_D_OC";
25"IRQ_SML1_PMBUS_ALERT_N";
26"SMB_SML1_PMBUS_HSC_R1_SDA";
27"SMB_SML1_PMBUS_HSC_R1_SCL";
28"IRQ_HSC_FAULT_N";
29"HSC_CSOUT";
30"HSC_EN";
31"P3V3_AUX\g";
32"MB0_P12V_STBY_PWRGD";
33"HSC_TYPE_ADC";
34"GND\g";
35"P12V_HSC_TEMP_R";
36"P12V_HSC_TEMP_D+";
37"P12V_HSC_TEMP_D-";
38"P12V_HSC_T_CRIT_N";
39"P12V_HSC_TEMP_ALERT_N";
40"SMB_P12V_HSC_TEMP_SDA";
41"SMB_P12V_HSC_TEMP_SCL";
42"P12V_HSC_TEMP_ALERT_R_N";
43"SMB_P12V_HSC_SDA";
44"SMB_P12V_HSC_SCL";
45"P12V_HSC_GATE1";
46"A_HSC_LOW_GATE";
47"HSC_D_OC_R2";
48"HSC_OC_VOL";
49"OC_P2V5_COMP";
50"HSC_CSOUT";
51"A_HSC_LOW_GATE";
52"A_HSC_HIGH";
53"A_HSC_LOW";
54"U142_VS";
55"HSC_CSOUT";
56"P12V_HSC_SENSE2_N";
57"P12V_HSC_GATE2";
58"P12V_HSC_T_CRIT_R_N";
59"P12V_HSC_ADC_P";
60"P12V_HSC_ADC_N";
61"P12V_HSC_SENSE2_P";
62"P12V_HSC_SENSE1_N";
63"P12V_HSC_SENSE1_P";
64"SMB_P12V_HSC_SDA";
65"SMB_P12V_HSC_SCL";
66"P12V_HSC_TEMP_E";
67"A_HSC_LOW_DRAIN";
68"P12V_AUX\g";
69"GND\g";
70"P3V3_AUX\g";
71"GND\g";
72"GND\g";
%"METR3904G"
"1","(-6100,1950)","2","pure_quanta","I1";
;
LOCATION"Q6001"
$SEC"1"
CDS_SEC"1"
MATERIAL"IC"
ROOM"HSC BOM2"
VALUE"METR3904-G"
PART_TYPE"SMLF"
NEEDS_NO_SIZE"TRUE"
CDS_LIB"pure_quanta"
PART_NUMBER"BA039040020";
"3"
$PN"C"35;
"1"
$PN"B"35;
"2"
$PN"E"66;
%"Q_RES"
"1","(-2500,2025)","0","pure_quanta","I10";
;
LOCATION"R2628"
$SEC"1"
CDS_SEC"1"
ROOM"HSC BOM2"
MATERIAL"CHIP"
VALUE"0"
TOLERANCE"5%"
PACK_TYPE"0402LF"
WATTAGE"1/16W"
CDS_LIB"pure_quanta"
PART_NUMBER"CS00002JB13";
"B"
$PN"2"42;
"A"
$PN"1"39;
%"UNIVERSAL_POWER"
"1","(-4550,4075)","0","pure_quanta_power","I100";
;
HDL_POWER"P3V3_AUX"
CDS_LIB"pure_quanta_power";
"A"1;
%"LM4040AIM3X25NOPB"
"1","(-8525,2875)","0","pure_quanta","I101";
;
LOCATION"U8005"
$SEC"1"
CDS_SEC"1"
ROOM"HSC BOM2"
PART_TYPE"SMLF"
MATERIAL"EMPTY"
VALUE"LM4040AIM3X-2.5/NOPB"
CDS_LIB"pure_quanta"
PIN_NAMES_ROTATE"True"
CDS_LMAN_SYM_OUTLINE"-200,250,200,-250"
PART_NUMBER"AL404025013";
"3"
$PN"3"0;
"2-"
$PN"2"14;
"1+"
$PN"1"49;
%"Q_RES"
"1","(-6300,3800)","0","pure_quanta","I103";
;
LOCATION"R8112"
$SEC"1"
CDS_SEC"1"
TOLERANCE"1%"
ROOM"HSC BOM2"
VALUE"1M"
PACK_TYPE"0402LF"
MATERIAL"EMPTY"
WATTAGE"1/16W"
CDS_LIB"pure_quanta"
PART_NUMBER"CS51002FB05";
"B"
$PN"2"47;
"A"
$PN"1"48;
%"AP331AWG7"
"1","(-6750,3475)","0","pure_quanta","I104";
;
LOCATION"U8006"
$SEC"1"
CDS_SEC"1"
PART_TYPE"SMLF"
MATERIAL"EMPTY"
VALUE"AP331AWG-7"
ROOM"HSC BOM2"
CDS_LIB"pure_quanta"
NEEDS_NO_SIZE"TRUE"
CDS_LMAN_SYM_OUTLINE"-100,100,100,-100"
PART_NUMBER"AL000331011";
"GND"
$PN"2"20;
"VCC"
$PN"5"68;
"OUTPUT"
$PN"4"47;
"IN-"
$PN"1"49;
"IN+"
$PN"3"48;
%"GND"
"1","(-6825,5975)","0","pure_quanta_power","I106";
;
SIZE"1B"
ROOM"VR_DDR1_POWER_STAGE"
CDS_LIB"pure_quanta_power"
HDL_POWER"GND";
"A<SIZE-1..0>\NAC"72;
%"Q_CAP"
"1","(-6825,6275)","0","pure_quanta","I107";
;
LOCATION"C6084"
$SEC"1"
CDS_SEC"1"
VOLTAGE"25V"
TOLERANCE"10%"
PACK_TYPE"0402"
VALUE"0.1UF"
MATERIAL"EMPTY"
ROOM"HSC BOM2"
CDS_LIB"pure_quanta"
PART_NUMBER"CH4104K1B00";
"B"
$PN"2"72;
"A"
$PN"1"54;
%"Q_RES"
"2","(-6375,6625)","0","pure_quanta","I108";
;
LOCATION"R9020"
$SEC"1"
CDS_SEC"1"
PACK_TYPE"0402LF"
MATERIAL"EMPTY"
WATTAGE"1/16W"
TOLERANCE"1%"
VALUE"1K"
ROOM"HSC BOM2"
CDS_LIB"pure_quanta"
PART_NUMBER"CS21002FB06";
"A"
$PN"1"2;
"B"
$PN"2"54;
%"UNIVERSAL_POWER"
"1","(-6375,6825)","0","pure_quanta_power","I109";
;
HDL_POWER"P3V3_AUX"
CDS_LIB"pure_quanta_power";
"A"2;
%"Q_CAP"
"1","(-6375,6250)","2","pure_quanta","I110";
;
LOCATION"C9003"
$SEC"1"
CDS_SEC"1"
ROOM"HSC BOM2"
PACK_TYPE"C0402"
MATERIAL"EMPTY"
TOLERANCE"10%"
VALUE"1UF"
VOLTAGE"25V"
CDS_LIB"pure_quanta"
PART_NUMBER"CH5104KEB02";
"B"
$PN"2"72;
"A"
$PN"1"54;
%"UNIVERSAL_POWER"
"1","(-2700,4825)","0","pure_quanta_power","I112";
;
HDL_POWER"P3V3_AUX"
CDS_LIB"pure_quanta_power";
"A"3;
%"Q_RES"
"2","(-2700,4625)","2","pure_quanta","I113";
;
LOCATION"R9024"
SEC"1"
WATTAGE"1/16W"
ROOM"HSC BOM2"
TOLERANCE"1%"
MATERIAL"CHIP"
PACK_TYPE"0402LF"
VALUE"54.9K"
CDS_LIB"pure_quanta"
SEC_TYPE"0402LF"
PART_NUMBER"CS35492FB03";
"A"
$PN"1"3;
"B"
$PN"2"28;
%"Q_RES"
"1","(-5300,1775)","0","pure_quanta","I2";
;
LOCATION"R2624"
$SEC"1"
CDS_SEC"1"
TOLERANCE"1%"
VALUE"49.9"
ROOM"HSC BOM2"
MATERIAL"CHIP"
PACK_TYPE"0402LF"
WATTAGE"1/16W"
CDS_LIB"pure_quanta"
PART_NUMBER"CS04992FB07";
"B"
$PN"2"37;
"A"
$PN"1"66;
%"UNIVERSAL_GND"
"1","(-2150,3525)","0","pure_quanta_power","I24";
;
CDS_LIB"pure_quanta_power"
HDL_POWER"GND";
"A"34;
%"UNIVERSAL_POWER"
"1","(-2400,4450)","0","pure_quanta_power","I25";
;
HDL_POWER"P3V3_AUX"
CDS_LIB"pure_quanta_power";
"A"31;
%"UNIVERSAL_GND"
"1","(-1300,3675)","0","pure_quanta_power","I26";
;
CDS_LIB"pure_quanta_power"
HDL_POWER"GND";
"A"71;
%"UNIVERSAL_GND"
"1","(-925,3450)","0","pure_quanta_power","I27";
;
CDS_LIB"pure_quanta_power"
HDL_POWER"GND";
"A"4;
%"Q_CAP"
"1","(-925,3625)","0","pure_quanta","I28";
;
LOCATION"PC1789"
$SEC"1"
CDS_SEC"1"
ROOM"HSC BOM2"
VOLTAGE"25V"
MATERIAL"X7R"
VALUE"0.1UF"
PACK_TYPE"0402"
TOLERANCE"10%"
CDS_LIB"pure_quanta"
PART_NUMBER"CH4104K1B00";
"B"
$PN"2"4;
"A"
$PN"1"22;
%"UNIVERSAL_POWER"
"1","(-800,4450)","0","pure_quanta_power","I29";
;
HDL_POWER"P12V_PSU"
BOM_COST"MIO_VRD_SB"
ROOM"AUX_SW"
CDS_LIB"pure_quanta_power";
"A"5;
%"Q_RES"
"1","(-5275,2125)","0","pure_quanta","I3";
;
LOCATION"R2625"
$SEC"1"
CDS_SEC"1"
VALUE"49.9"
ROOM"HSC BOM2"
TOLERANCE"1%"
MATERIAL"CHIP"
PACK_TYPE"0402LF"
WATTAGE"1/16W"
CDS_LIB"pure_quanta"
PART_NUMBER"CS04992FB07";
"B"
$PN"2"36;
"A"
$PN"1"35;
%"UNIVERSAL_POWER"
"1","(-175,3950)","0","pure_quanta_power","I34";
;
HDL_POWER"P12V_AUX"
CDS_LIB"pure_quanta_power";
"A"22;
%"Q_RES"
"1","(-2500,2125)","0","pure_quanta","I39";
;
LOCATION"R2627"
$SEC"1"
CDS_SEC"1"
ROOM"HSC BOM2"
MATERIAL"CHIP"
WATTAGE"1/16W"
VALUE"0"
PACK_TYPE"0402LF"
TOLERANCE"5%"
CDS_LIB"pure_quanta"
PART_NUMBER"CS00002JB13";
"B"
$PN"2"43;
"A"
$PN"1"40;
%"Q_CAP"
"1","(-4975,1975)","2","pure_quanta","I4";
;
LOCATION"C1786"
$SEC"1"
CDS_SEC"1"
VALUE"1000PF"
VOLTAGE"50V"
TOLERANCE"10%"
MATERIAL"X7R"
ROOM"HSC BOM2"
PACK_TYPE"0603"
CDS_LIB"pure_quanta"
PART_NUMBER"TMP_QCH21006K917";
"B"
$PN"2"37;
"A"
$PN"1"36;
%"Q_RES"
"1","(-2500,2225)","0","pure_quanta","I40";
;
LOCATION"R2626"
$SEC"1"
CDS_SEC"1"
ROOM"HSC BOM2"
WATTAGE"1/16W"
TOLERANCE"5%"
MATERIAL"CHIP"
PACK_TYPE"0402LF"
VALUE"0"
CDS_LIB"pure_quanta"
PART_NUMBER"CS00002JB13";
"B"
$PN"2"44;
"A"
$PN"1"41;
%"SCONN21_9193031121LF"
"1","(-1700,4025)","2","pure_quanta","I42";
;
LOCATION"PJ38"
SEC"1"
MATERIAL"IO"
ROOM"HSC BOM2"
PART_TYPE"SMLF"
VALUE"SCONN21_91930-31121LF"
SEC_TYPE""
CDS_LIB"pure_quanta"
NEEDS_NO_SIZE"TRUE"
CDS_LMAN_SYM_OUTLINE"-150,425,150,-425"
PART_NUMBER"DFHS21FS003";
"21"
$PN"21"34;
"20"
$PN"20"25;
"19"
$PN"19"26;
"18"
$PN"18"27;
"17"
$PN"17"33;
"16"
$PN"16"29;
"15"
$PN"15"32;
"14"
$PN"14"30;
"13"
$PN"13"28;
"12"
$PN"12"31;
"11"
$PN"11"71;
"10"
$PN"10"22;
"9"
$PN"9"57;
"8"
$PN"8"45;
"7"
$PN"7"59;
"6"
$PN"6"60;
"G2"
$PN"G2"34;
"G1"
$PN"G1"34;
"2"
$PN"2"63;
"5"
$PN"5"56;
"4"
$PN"4"61;
"3"
$PN"3"62;
"1"
$PN"1"5;
%"Q_RES"
"2","(-1450,2825)","2","pure_quanta","I45";
;
LOCATION"R6230"
$SEC"1"
CDS_SEC"1"
TOLERANCE"5%"
PACK_TYPE"0402LF"
MATERIAL"CHIP"
WATTAGE"1/16W"
VALUE"2.2K"
ROOM"HSC BOM2"
CDS_LIB"pure_quanta"
PART_NUMBER"CS22202JB07";
"A"
$PN"1"70;
"B"
$PN"2"64;
%"Q_RES"
"2","(-1325,2850)","0","pure_quanta","I46";
;
LOCATION"R6231"
$SEC"1"
CDS_SEC"1"
PACK_TYPE"0402LF"
MATERIAL"CHIP"
VALUE"2.2K"
ROOM"HSC BOM2"
WATTAGE"1/16W"
TOLERANCE"5%"
CDS_LIB"pure_quanta"
PART_NUMBER"CS22202JB07";
"A"
$PN"1"70;
"B"
$PN"2"65;
%"UNIVERSAL_POWER"
"1","(-1450,3100)","0","pure_quanta_power","I47";
;
HDL_POWER"P3V3_AUX"
CDS_LIB"pure_quanta_power";
"A"70;
%"UNIVERSAL_GND"
"1","(-4750,2250)","0","pure_quanta_power","I5";
;
CDS_LIB"pure_quanta_power"
HDL_POWER"GND";
"A"6;
%"LT6700CS61TRPBF"
"1","(-5500,5800)","0","pure_quanta","I50";
;
LOCATION"U142"
SEC"1"
ROOM"HSC BOM2"
PART_TYPE"SMLF"
VALUE"LT6700CS6-1#TRPBF"
MATERIAL"EMPTY"
SEC_TYPE""
CDS_LIB"pure_quanta"
CDS_LMAN_SYM_OUTLINE"-225,150,225,-150"
NEEDS_NO_SIZE"TRUE"
PART_NUMBER"AL006700001";
"OUTB"
$PN"6"24;
"INA+"
$PN"3"53;
"OUTA"
$PN"1"51;
"GND"
$PN"2"7;
"INB-"
$PN"4"52;
"VS"
$PN"5"54;
%"Q_RES"
"2","(-7300,6225)","0","pure_quanta","I55";
;
LOCATION"R6234"
$SEC"1"
CDS_SEC"1"
TOLERANCE"1%"
ROOM"HSC BOM2"
VALUE"160K"
WATTAGE"1/16W"
MATERIAL"EMPTY"
PACK_TYPE"0402LF"
CDS_LIB"pure_quanta"
PART_NUMBER"CS41602FB05";
"A"
$PN"1"55;
"B"
$PN"2"52;
%"Q_RES"
"2","(-7775,6200)","0","pure_quanta","I56";
;
LOCATION"R6232"
$SEC"1"
CDS_SEC"1"
TOLERANCE"1%"
VALUE"160K"
ROOM"HSC BOM2"
WATTAGE"1/16W"
MATERIAL"EMPTY"
PACK_TYPE"0402LF"
CDS_LIB"pure_quanta"
PART_NUMBER"CS41602FB05";
"A"
$PN"1"55;
"B"
$PN"2"53;
%"Q_RES"
"2","(-7775,5475)","0","pure_quanta","I57";
;
LOCATION"R6233"
$SEC"1"
CDS_SEC"1"
PACK_TYPE"0402LF"
VALUE"10K"
MATERIAL"EMPTY"
WATTAGE"1/16W"
ROOM"HSC BOM2"
TOLERANCE"1%"
CDS_LIB"pure_quanta"
PART_NUMBER"CS31002FB08";
"A"
$PN"1"53;
"B"
$PN"2"69;
%"Q_RES"
"2","(-7300,5425)","0","pure_quanta","I58";
;
LOCATION"R6235"
$SEC"1"
CDS_SEC"1"
PACK_TYPE"0402LF"
TOLERANCE"1%"
WATTAGE"1/16W"
MATERIAL"EMPTY"
VALUE"10K"
ROOM"HSC BOM2"
CDS_LIB"pure_quanta"
PART_NUMBER"CS31002FB08";
"A"
$PN"1"52;
"B"
$PN"2"69;
%"Q_CAP"
"1","(-4750,2450)","0","pure_quanta","I6";
;
LOCATION"C1787"
$SEC"1"
CDS_SEC"1"
VOLTAGE"16V"
TOLERANCE"10%"
MATERIAL"X7R"
PACK_TYPE"C0402"
ROOM"HSC BOM2"
VALUE"0.1UF"
CDS_LIB"pure_quanta"
PART_NUMBER"CH4103K1B08";
"B"
$PN"2"6;
"A"
$PN"1"23;
%"GND"
"1","(-7775,5000)","0","pure_quanta_power","I60";
;
CDS_LIB"pure_quanta_power"
SIZE"1B"
ROOM"VR_DDR1_POWER_STAGE"
HDL_POWER"GND";
"A<SIZE-1..0>\NAC"69;
%"GND"
"1","(-5025,5400)","0","pure_quanta_power","I61";
;
ROOM"VR_DDR1_POWER_STAGE"
SIZE"1B"
CDS_LIB"pure_quanta_power"
HDL_POWER"GND";
"A<SIZE-1..0>\NAC"7;
%"Q_RES"
"2","(-4450,6225)","0","pure_quanta","I63";
;
LOCATION"R6236"
$SEC"1"
CDS_SEC"1"
PACK_TYPE"0402LF"
MATERIAL"EMPTY"
TOLERANCE"1%"
VALUE"10K"
ROOM"HSC BOM2"
WATTAGE"1/16W"
CDS_LIB"pure_quanta"
PART_NUMBER"CS31002FB08";
"A"
$PN"1"8;
"B"
$PN"2"51;
%"UNIVERSAL_POWER"
"1","(-4450,6525)","0","pure_quanta_power","I64";
;
HDL_POWER"P3V3_AUX"
CDS_LIB"pure_quanta_power";
"A"8;
%"Q_RES"
"2","(-4450,5525)","0","pure_quanta","I66";
;
LOCATION"R6237"
$SEC"1"
CDS_SEC"1"
MATERIAL"EMPTY"
VALUE"0"
PACK_TYPE"0402LF"
ROOM"HSC BOM2"
TOLERANCE"5%"
WATTAGE"1/16W"
CDS_LIB"pure_quanta"
PART_NUMBER"CS00002JB13";
"A"
$PN"1"51;
"B"
$PN"2"9;
%"GND"
"1","(-4450,5200)","0","pure_quanta_power","I67";
;
CDS_LIB"pure_quanta_power"
SIZE"1B"
ROOM"VR_DDR1_POWER_STAGE"
HDL_POWER"GND";
"A<SIZE-1..0>\NAC"9;
%"MOSFET_NCH_GDS_ESD_PROTECTED"
"1","(-3450,6275)","0","pure_quanta","I68";
;
LOCATION"U6004"
$SEC"1"
CDS_SEC"1"
VALUE"2N7002K"
MATERIAL"EMPTY"
PART_TYPE"SMLF"
ROOM"HSC BOM2"
CDS_LIB"pure_quanta"
NEEDS_NO_SIZE"TRUE"
CDS_LMAN_SYM_OUTLINE"-125,150,125,-150"
PART_NUMBER"BAM70020002";
"S"
$PN"S"10;
"G"
$PN"G"51;
"D"
$PN"D"67;
%"GND"
"1","(-3425,5900)","0","pure_quanta_power","I69";
;
SIZE"1B"
ROOM"VR_DDR1_POWER_STAGE"
CDS_LIB"pure_quanta_power"
HDL_POWER"GND";
"A<SIZE-1..0>\NAC"10;
%"UNIVERSAL_POWER"
"1","(-4575,2850)","0","pure_quanta_power","I7";
;
HDL_POWER"P3V3_AUX"
CDS_LIB"pure_quanta_power";
"A"23;
%"Q_RES"
"2","(-2300,6175)","0","pure_quanta","I70";
;
LOCATION"R6239"
$SEC"1"
CDS_SEC"1"
ROOM"HSC BOM2"
WATTAGE"1/16W"
MATERIAL"CHIP"
PACK_TYPE"0402LF"
TOLERANCE"1%"
VALUE"10K"
CDS_LIB"pure_quanta"
PART_NUMBER"CS31002FB08";
"A"
$PN"1"11;
"B"
$PN"2"24;
%"UNIVERSAL_POWER"
"1","(-2300,6550)","0","pure_quanta_power","I71";
;
HDL_POWER"P3V3_AUX"
CDS_LIB"pure_quanta_power";
"A"11;
%"Q_RES"
"2","(-2775,6225)","0","pure_quanta","I72";
;
LOCATION"R6238"
$SEC"1"
CDS_SEC"1"
PACK_TYPE"0402LF"
ROOM"HSC BOM2"
MATERIAL"EMPTY"
WATTAGE"1/16W"
TOLERANCE"5%"
VALUE"0"
CDS_LIB"pure_quanta"
PART_NUMBER"CS00002JB13";
"A"
$PN"1"67;
"B"
$PN"2"24;
%"Q_RES"
"1","(-5275,4925)","0","pure_quanta","I73";
;
LOCATION"R6210"
$SEC"1"
CDS_SEC"1"
TOLERANCE"5%"
ROOM"HSC BOM2"
MATERIAL"CHIP"
PACK_TYPE"0402LF"
VALUE"0"
WATTAGE"1/16W"
CDS_LIB"pure_quanta"
PART_NUMBER"CS00002JB13";
"B"
$PN"2"24;
"A"
$PN"1"55;
%"Q_RES"
"1","(-3500,1250)","0","pure_quanta","I74";
;
LOCATION"R353"
$SEC"1"
CDS_SEC"1"
MATERIAL"CHIP"
VALUE"0"
TOLERANCE"5%"
WATTAGE"1/16W"
PACK_TYPE"0402LF"
ROOM"HSC BOM2"
CDS_LIB"pure_quanta"
PART_NUMBER"CS00002JB13";
"B"
$PN"2"58;
"A"
$PN"1"38;
%"Q_RES"
"2","(-2275,1600)","0","pure_quanta","I76";
;
LOCATION"R354"
$SEC"1"
CDS_SEC"1"
PACK_TYPE"0402LF"
TOLERANCE"1%"
WATTAGE"1/16W"
MATERIAL"CHIP"
ROOM"HSC BOM2"
VALUE"10.5K"
CDS_LIB"pure_quanta"
PART_NUMBER"CS31052FB03";
"A"
$PN"1"12;
"B"
$PN"2"58;
%"UNIVERSAL_POWER"
"1","(-2275,1850)","0","pure_quanta_power","I77";
;
HDL_POWER"P3V3_AUX"
CDS_LIB"pure_quanta_power";
"A"12;
%"UNIVERSAL_POWER"
"1","(-2125,2875)","0","pure_quanta_power","I78";
;
HDL_POWER"P3V3_AUX"
CDS_LIB"pure_quanta_power";
"A"13;
%"Q_RES"
"2","(-2125,2600)","2","pure_quanta","I79";
;
LOCATION"R355"
$SEC"1"
CDS_SEC"1"
VALUE"10.5K"
ROOM"HSC BOM2"
TOLERANCE"1%"
WATTAGE"1/16W"
PACK_TYPE"0402LF"
MATERIAL"CHIP"
CDS_LIB"pure_quanta"
PART_NUMBER"CS31052FB03";
"A"
$PN"1"13;
"B"
$PN"2"42;
%"NCT7718W"
"1","(-3825,2075)","0","pure_quanta","I8";
;
LOCATION"U143"
$SEC"1"
CDS_SEC"1"
ROOM"HSC BOM2"
MATERIAL"IC"
VALUE"NCT7718W"
PART_TYPE"SMLF"
NEEDS_NO_SIZE"TRUE"
CDS_LIB"pure_quanta"
CDS_LMAN_SYM_OUTLINE"-250,200,250,-200"
PART_NUMBER"AL007718001";
"SCL"
$PN"8"41;
"SDA"
$PN"7"40;
"ALERT# \B"
$PN"6"39;
"GND"
$PN"5"19;
"T_CRIT# \B"
$PN"4"38;
"D-"
$PN"3"37;
"D+"
$PN"2"36;
"VDD"
$PN"1"23;
%"UNIVERSAL_GND"
"1","(-8900,2550)","0","pure_quanta_power","I80";
;
CDS_LIB"pure_quanta_power"
HDL_POWER"GND";
"A"14;
%"Q_RES"
"2","(-8925,3700)","0","pure_quanta","I81";
;
LOCATION"R8107"
$SEC"1"
CDS_SEC"1"
PACK_TYPE"0402LF"
ROOM"HSC BOM2"
MATERIAL"EMPTY"
TOLERANCE"1%"
WATTAGE"1/16W"
VALUE"10K"
CDS_LIB"pure_quanta"
PART_NUMBER"CS31002FB08";
"A"
$PN"1"16;
"B"
$PN"2"49;
%"Q_RES"
"2","(-7925,3075)","0","pure_quanta","I82";
;
LOCATION"R8109"
$SEC"1"
CDS_SEC"1"
ROOM"HSC BOM2"
MATERIAL"EMPTY"
VALUE"10K"
WATTAGE"1/16W"
TOLERANCE"1%"
PACK_TYPE"0402LF"
CDS_LIB"pure_quanta"
PART_NUMBER"CS31002FB08";
"A"
$PN"1"48;
"B"
$PN"2"15;
%"UNIVERSAL_GND"
"1","(-7925,2800)","0","pure_quanta_power","I83";
;
CDS_LIB"pure_quanta_power"
HDL_POWER"GND";
"A"15;
%"Q_RES"
"2","(-7925,3750)","0","pure_quanta","I84";
;
LOCATION"R8108"
$SEC"1"
CDS_SEC"1"
WATTAGE"1/16W"
TOLERANCE"1%"
VALUE"160K"
ROOM"HSC BOM2"
PACK_TYPE"0402LF"
MATERIAL"EMPTY"
CDS_LIB"pure_quanta"
PART_NUMBER"CS41602FB05";
"A"
$PN"1"50;
"B"
$PN"2"48;
%"UNIVERSAL_POWER"
"1","(-8925,4025)","0","pure_quanta_power","I85";
;
HDL_POWER"P3V3_AUX"
CDS_LIB"pure_quanta_power";
"A"16;
%"UNIVERSAL_GND"
"1","(-7525,2800)","0","pure_quanta_power","I86";
;
CDS_LIB"pure_quanta_power"
HDL_POWER"GND";
"A"17;
%"Q_CAP"
"1","(-7525,3075)","2","pure_quanta","I87";
;
LOCATION"C8014"
$SEC"1"
CDS_SEC"1"
VALUE"100NF"
VOLTAGE"50V"
TOLERANCE"10%"
PACK_TYPE"C0402"
MATERIAL"EMPTY"
ROOM"HSC BOM2"
CDS_LIB"pure_quanta"
PART_NUMBER"CH4106K1B01";
"B"
$PN"2"17;
"A"
$PN"1"49;
%"UNIVERSAL_GND"
"1","(-7100,2800)","0","pure_quanta_power","I88";
;
CDS_LIB"pure_quanta_power"
HDL_POWER"GND";
"A"18;
%"Q_CAP"
"1","(-7100,3075)","2","pure_quanta","I89";
;
LOCATION"C8015"
$SEC"1"
CDS_SEC"1"
TOLERANCE"10%"
MATERIAL"EMPTY"
VOLTAGE"50V"
PACK_TYPE"C0402"
ROOM"HSC BOM2"
VALUE"100NF"
CDS_LIB"pure_quanta"
PART_NUMBER"CH4106K1B01";
"B"
$PN"2"18;
"A"
$PN"1"48;
%"UNIVERSAL_GND"
"1","(-3325,1800)","0","pure_quanta_power","I9";
;
CDS_LIB"pure_quanta_power"
HDL_POWER"GND";
"A"19;
%"UNIVERSAL_GND"
"1","(-6750,3050)","0","pure_quanta_power","I90";
;
CDS_LIB"pure_quanta_power"
HDL_POWER"GND";
"A"20;
%"UNIVERSAL_POWER"
"1","(-6750,4325)","0","pure_quanta_power","I93";
;
HDL_POWER"P12V_AUX"
CDS_LIB"pure_quanta_power";
"A"68;
%"UNIVERSAL_GND"
"1","(-6500,3900)","0","pure_quanta_power","I94";
;
CDS_LIB"pure_quanta_power"
HDL_POWER"GND";
"A"21;
%"Q_CAP"
"1","(-6500,4100)","2","pure_quanta","I95";
;
LOCATION"C8016"
$SEC"1"
CDS_SEC"1"
VALUE"100NF"
MATERIAL"EMPTY"
TOLERANCE"10%"
VOLTAGE"50V"
ROOM"HSC BOM2"
PACK_TYPE"C0402"
CDS_LIB"pure_quanta"
PART_NUMBER"CH4106K1B01";
"B"
$PN"2"21;
"A"
$PN"1"68;
%"Q_RES"
"1","(-5375,3475)","0","pure_quanta","I96";
;
LOCATION"R8110"
$SEC"1"
CDS_SEC"1"
VALUE"33.2"
MATERIAL"EMPTY"
TOLERANCE"1%"
ROOM"HSC BOM2"
PACK_TYPE"0402LF"
WATTAGE"1/16W"
CDS_LIB"pure_quanta"
PART_NUMBER"CS03322FB03";
"B"
$PN"2"46;
"A"
$PN"1"47;
%"Q_RES"
"2","(-4550,3750)","0","pure_quanta","I98";
;
LOCATION"R8111"
$SEC"1"
CDS_SEC"1"
ROOM"HSC BOM2"
TOLERANCE"1%"
VALUE"10K"
WATTAGE"1/16W"
MATERIAL"EMPTY"
PACK_TYPE"0402LF"
CDS_LIB"pure_quanta"
PART_NUMBER"CS31002FB08";
"A"
$PN"1"1;
"B"
$PN"2"46;
END.
